FILE_TYPE = MACRO_DRAWING;
SET COLOR_WIRE YELLOW;
SET COLOR_PROP ORANGE;
SET COLOR_DOT WHITE;
SET COLOR_ARC YELLOW;
SET COLOR_BODY GREEN;
SET COLOR_NOTE PURPLE;
SET PROP_DISPLAY VALUE;
SET PAGE_NUMBER P390;
FORCEADD QUANTA_TITLE_BLOCK_C..1
(0 0);
FORCEPROP 1 LAST CUSTOM_TXT_CDS <NAME_2>
J 0
(-3175 50);
FORCEPROP 1 LAST CUSTOM_TXT_CDS <NAME_1>
J 0
(-3175 175);
FORCEPROP 1 LAST CUSTOM_TXT_CDS <Q_NUMBER>
J 0
(-1403 103);
DISPLAY 1.212766 (-1403 103);
FORCEPROP 1 LAST CUSTOM_TXT_CDS <Q_PROJ>
J 0
(-2382 102);
DISPLAY 1.212766 (-2382 102);
FORCEPROP 1 LAST CUSTOM_TXT_CDS <Q_REV>
J 0
(-184 103);
DISPLAY 1.212766 (-184 103);
FORCEPROP 1 LAST CUSTOM_TXT_CDS <CON_LAST_MODIFIED>
J 0
(-1885 15);
DISPLAY 0.978723 (-1885 15);
FORCEPROP 1 LAST CUSTOM_TXT_CDS <CON_PAGE_NUM> OF <CON_TOTAL_PAGES>
J 0
(-446 18);
DISPLAY 0.978723 (-446 18);
FORCEPROP 1 LAST Q_TITLE RETIMER_CPU0_P0(10)
J 0
(-9366 26);
DISPLAY 2.446809 (-9366 26);
PAINT GREEN (-9366 26);
FORCEPROP 1 LAST CDS_LMAN_SYM_OUTLINE -9475,6775,100,-125
J 0
(0 0);
DISPLAY 0.468085 (0 0);
PAINT GREEN (0 0);
DISPLAY INVISIBLE (0 0);
FORCEPROP 2 LAST CDS_LIB pure_quanta
J 0
(0 0);
DISPLAY INVISIBLE (0 0);
FORCEPROP 2 LAST PAGE_BORDER TRUE
J 0
(-7890 5250);
DISPLAY 0.638298 (-7890 5250);
PAINT PINK (-7890 5250);
DISPLAY INVISIBLE (-7890 5250);
FORCEPROP 2 LAST CDS_XR_PAGE_TITLE CR-282 : @T6G_MB_LIB.T6G(SCH_1):PAGE282
J 0
(-7890 5250);
DISPLAY 0.638298 (-7890 5250);
PAINT PINK (-7890 5250);
DISPLAY INVISIBLE (-7890 5250);
FORCEPROP 2 LAST CUSTOM_TXT_CDS <XR_PAGE_TITLE>
J 0
(-7890 5250);
DISPLAY 0.638298 (-7890 5250);
PAINT PINK (-7890 5250);
DISPLAY INVISIBLE (-7890 5250);
FORCEPROP 1 LAST COMMENT_BODY TRUE
J 0
(12 -13);
DISPLAY 0.978723 (12 -13);
PAINT GREEN (12 -13);
DISPLAY INVISIBLE (12 -13);
FORCEPROP 1 LAST Q_DEPT BU9
J 1
(-3763 49);
DISPLAY 1.957447 (-3763 49);
PAINT GREEN (-3763 49);
DISPLAY INVISIBLE (-3763 49);
FORCEPROP 0 LAST CDS_CON_LAST_MODIFIED Thu Aug 24 10:16:09 2023
J 0
(-1885 15);
DISPLAY INVISIBLE (-1885 15);
QUIT
